(kicad_pcb
	(version 20260206)
	(generator "pcbnew")
	(generator_version "10.0")
	(general
		(thickness 1.6)
		(legacy_teardrops no)
	)
	(paper "A4")
	(title_block
		(title "04192023_DAF0TMB3IC0_F0TG_MB_C_brd_V02_OCP.brd")
		(comment 1 "Grand Teton / footprints 4118-4123 of 8354")
	)
	(layers
		(0 "F.Cu" signal "TOP")
		(4 "In1.Cu" signal "GND")
		(6 "In2.Cu" signal "IN1")
		(8 "In3.Cu" signal "GND1")
		(10 "In4.Cu" signal "IN2")
		(12 "In5.Cu" signal "GND2")
		(14 "In6.Cu" signal "IN3")
		(16 "In7.Cu" signal "GND3")
		(18 "In8.Cu" signal "VCC")
		(20 "In9.Cu" signal "VCC1")
		(22 "In10.Cu" signal "GND4")
		(24 "In11.Cu" signal "IN4")
		(26 "In12.Cu" signal "GND5")
		(28 "In13.Cu" signal "IN5")
		(30 "In14.Cu" signal "GND6")
		(32 "In15.Cu" signal "IN6")
		(34 "In16.Cu" signal "GND7")
		(2 "B.Cu" signal "BOTTOM")
		(9 "F.Adhes" user "F.Adhesive")
		(11 "B.Adhes" user "B.Adhesive")
		(13 "F.Paste" user "Package Geometry/Pastemask Top")
		(15 "B.Paste" user "Package Geometry/Pastemask Bottom")
		(5 "F.SilkS" user "Ref Des/Silkscreen Top")
		(7 "B.SilkS" user "Ref Des/Silkscreen Bottom")
		(1 "F.Mask" user "Board Geometry/Soldermask Top")
		(3 "B.Mask" user "Board Geometry/Soldermask Bottom")
		(17 "Dwgs.User" user "User.Drawings")
		(19 "Cmts.User" user "User.Comments")
		(21 "Eco1.User" user "User.Eco1")
		(23 "Eco2.User" user "User.Eco2")
		(25 "Edge.Cuts" user "Board Geometry/Outline")
		(27 "Margin" user)
		(31 "F.CrtYd" user "Package Geometry/Place Bound Top")
		(29 "B.CrtYd" user "Package Geometry/Place Bound Bottom")
		(35 "F.Fab" user "Ref Des/Assembly Top")
		(33 "B.Fab" user "Ref Des/Assembly Bottom")
	)
	(footprint ""
		(layer "F.Cu")
		(at 340.527386 -416.899344 -90)
		(property "Reference" "C6526"
			(at 0 0 270)
			(layer "F.SilkS")
			(hide yes)
			(effects
				(font
					(size 1.27 1.27)
				)
			)
		)
		(property "Value" ""
			(at 0 0 270)
			(layer "F.Fab")
			(effects
				(font
					(size 1.27 1.27)
				)
			)
		)
		(duplicate_pad_numbers_are_jumpers no)
		(fp_line
			(start -0.299974 0.150114)
			(end -0.299974 -0.150114)
			(stroke
				(width 0.1)
				(type default)
			)
			(layer "F.Fab")
		)
		(fp_line
			(start 0.299974 0.150114)
			(end -0.299974 0.150114)
			(stroke
				(width 0.1)
				(type default)
			)
			(layer "F.Fab")
		)
		(fp_line
			(start -0.299974 -0.150114)
			(end 0.299974 -0.150114)
			(stroke
				(width 0.1)
				(type default)
			)
			(layer "F.Fab")
		)
		(fp_line
			(start 0.299974 -0.150114)
			(end 0.299974 0.150114)
			(stroke
				(width 0.1)
				(type default)
			)
			(layer "F.Fab")
		)
		(pad "1" smd rect
			(at -0.2667 0 270)
			(size 0.3048 0.381)
			(layers "F.Cu" "F.Mask" "F.Paste")
			(net "P5E_CPU0_P0_TX_BUF_C_DN<12>")
		)
		(pad "2" smd rect
			(at 0.2667 0 270)
			(size 0.3048 0.381)
			(layers "F.Cu" "F.Mask" "F.Paste")
			(net "P5E_CPU0_P0_TX_BUF_DN<12>")
		)
	)
	(footprint ""
		(layer "F.Cu")
		(at 463.18932 -37.549836)
		(property "Reference" "R1594"
			(at 0 0 0)
			(layer "F.SilkS")
			(hide yes)
			(effects
				(font
					(size 1.27 1.27)
				)
			)
		)
		(property "Value" ""
			(at 0 0 0)
			(layer "F.Fab")
			(effects
				(font
					(size 1.27 1.27)
				)
			)
		)
		(duplicate_pad_numbers_are_jumpers no)
		(fp_line
			(start -0.7874 -0.4064)
			(end 0.7874 -0.4064)
			(stroke
				(width 0.1524)
				(type default)
			)
			(layer "F.SilkS")
		)
		(fp_line
			(start -0.7874 0.4064)
			(end -0.7874 -0.4064)
			(stroke
				(width 0.1524)
				(type default)
			)
			(layer "F.SilkS")
		)
		(fp_line
			(start 0.7874 -0.4064)
			(end 0.7874 0.4064)
			(stroke
				(width 0.1524)
				(type default)
			)
			(layer "F.SilkS")
		)
		(fp_line
			(start 0.7874 0.4064)
			(end -0.7874 0.4064)
			(stroke
				(width 0.1524)
				(type default)
			)
			(layer "F.SilkS")
		)
		(fp_line
			(start -0.67945 -0.305054)
			(end -0.12065 -0.305054)
			(stroke
				(width 0.1)
				(type default)
			)
			(layer "F.Fab")
		)
		(fp_line
			(start -0.67945 0.3048)
			(end -0.67945 -0.305054)
			(stroke
				(width 0.1)
				(type default)
			)
			(layer "F.Fab")
		)
		(fp_line
			(start -0.12065 -0.305054)
			(end -0.12065 -0.2794)
			(stroke
				(width 0.1)
				(type default)
			)
			(layer "F.Fab")
		)
		(fp_line
			(start -0.12065 -0.2794)
			(end 0.12065 -0.2794)
			(stroke
				(width 0.1)
				(type default)
			)
			(layer "F.Fab")
		)
		(fp_line
			(start -0.12065 0.2794)
			(end -0.12065 0.3048)
			(stroke
				(width 0.1)
				(type default)
			)
			(layer "F.Fab")
		)
		(fp_line
			(start -0.12065 0.3048)
			(end -0.67945 0.3048)
			(stroke
				(width 0.1)
				(type default)
			)
			(layer "F.Fab")
		)
		(fp_line
			(start 0.120396 0.2794)
			(end -0.12065 0.2794)
			(stroke
				(width 0.1)
				(type default)
			)
			(layer "F.Fab")
		)
		(fp_line
			(start 0.120396 0.3048)
			(end 0.120396 0.2794)
			(stroke
				(width 0.1)
				(type default)
			)
			(layer "F.Fab")
		)
		(fp_line
			(start 0.12065 -0.3048)
			(end 0.67945 -0.3048)
			(stroke
				(width 0.1)
				(type default)
			)
			(layer "F.Fab")
		)
		(fp_line
			(start 0.12065 -0.2794)
			(end 0.12065 -0.3048)
			(stroke
				(width 0.1)
				(type default)
			)
			(layer "F.Fab")
		)
		(fp_line
			(start 0.67945 -0.3048)
			(end 0.67945 0.3048)
			(stroke
				(width 0.1)
				(type default)
			)
			(layer "F.Fab")
		)
		(fp_line
			(start 0.67945 0.3048)
			(end 0.120396 0.3048)
			(stroke
				(width 0.1)
				(type default)
			)
			(layer "F.Fab")
		)
		(pad "1" smd circle
			(at -0.40005 0)
			(size 0 0)
			(layers "F.Cu" "F.Mask" "F.Paste")
			(net "OCP_SFF_WAKE_BUFF_N")
		)
		(pad "2" smd circle
			(at 0.40005 0)
			(size 0 0)
			(layers "F.Cu" "F.Mask" "F.Paste")
			(net "OCP_SFF_WAKE_BUFF_R_N")
		)
	)
	(footprint ""
		(layer "F.Cu")
		(at 419.230302 -440.012836 90)
		(property "Reference" "R2829"
			(at 0 0 90)
			(layer "F.SilkS")
			(hide yes)
			(effects
				(font
					(size 1.27 1.27)
				)
			)
		)
		(property "Value" ""
			(at 0 0 90)
			(layer "F.Fab")
			(effects
				(font
					(size 1.27 1.27)
				)
			)
		)
		(duplicate_pad_numbers_are_jumpers no)
		(fp_line
			(start 0.7874 -0.4064)
			(end 0.7874 0.4064)
			(stroke
				(width 0.1524)
				(type default)
			)
			(layer "F.SilkS")
		)
		(fp_line
			(start -0.7874 -0.4064)
			(end 0.7874 -0.4064)
			(stroke
				(width 0.1524)
				(type default)
			)
			(layer "F.SilkS")
		)
		(fp_line
			(start 0.7874 0.4064)
			(end -0.7874 0.4064)
			(stroke
				(width 0.1524)
				(type default)
			)
			(layer "F.SilkS")
		)
		(fp_line
			(start -0.7874 0.4064)
			(end -0.7874 -0.4064)
			(stroke
				(width 0.1524)
				(type default)
			)
			(layer "F.SilkS")
		)
		(fp_line
			(start -0.12065 -0.305054)
			(end -0.12065 -0.2794)
			(stroke
				(width 0.1)
				(type default)
			)
			(layer "F.Fab")
		)
		(fp_line
			(start -0.67945 -0.305054)
			(end -0.12065 -0.305054)
			(stroke
				(width 0.1)
				(type default)
			)
			(layer "F.Fab")
		)
		(fp_line
			(start 0.67945 -0.3048)
			(end 0.67945 0.3048)
			(stroke
				(width 0.1)
				(type default)
			)
			(layer "F.Fab")
		)
		(fp_line
			(start 0.12065 -0.3048)
			(end 0.67945 -0.3048)
			(stroke
				(width 0.1)
				(type default)
			)
			(layer "F.Fab")
		)
		(fp_line
			(start 0.12065 -0.2794)
			(end 0.12065 -0.3048)
			(stroke
				(width 0.1)
				(type default)
			)
			(layer "F.Fab")
		)
		(fp_line
			(start -0.12065 -0.2794)
			(end 0.12065 -0.2794)
			(stroke
				(width 0.1)
				(type default)
			)
			(layer "F.Fab")
		)
		(fp_line
			(start 0.120396 0.2794)
			(end -0.12065 0.2794)
			(stroke
				(width 0.1)
				(type default)
			)
			(layer "F.Fab")
		)
		(fp_line
			(start -0.12065 0.2794)
			(end -0.12065 0.3048)
			(stroke
				(width 0.1)
				(type default)
			)
			(layer "F.Fab")
		)
		(fp_line
			(start 0.67945 0.3048)
			(end 0.120396 0.3048)
			(stroke
				(width 0.1)
				(type default)
			)
			(layer "F.Fab")
		)
		(fp_line
			(start 0.120396 0.3048)
			(end 0.120396 0.2794)
			(stroke
				(width 0.1)
				(type default)
			)
			(layer "F.Fab")
		)
		(fp_line
			(start -0.12065 0.3048)
			(end -0.67945 0.3048)
			(stroke
				(width 0.1)
				(type default)
			)
			(layer "F.Fab")
		)
		(fp_line
			(start -0.67945 0.3048)
			(end -0.67945 -0.305054)
			(stroke
				(width 0.1)
				(type default)
			)
			(layer "F.Fab")
		)
		(pad "1" smd circle
			(at -0.40005 0 90)
			(size 0 0)
			(layers "F.Cu" "F.Mask" "F.Paste")
			(net "RST_BMC_FROM_SWB_N")
		)
		(pad "2" smd circle
			(at 0.40005 0 90)
			(size 0 0)
			(layers "F.Cu" "F.Mask" "F.Paste")
			(net "GND")
		)
	)
	(footprint ""
		(layer "F.Cu")
		(at 421.01643 -109.231176 -90)
		(property "Reference" "R1137"
			(at 0 0 270)
			(layer "F.SilkS")
			(hide yes)
			(effects
				(font
					(size 1.27 1.27)
				)
			)
		)
		(property "Value" ""
			(at 0 0 270)
			(layer "F.Fab")
			(effects
				(font
					(size 1.27 1.27)
				)
			)
		)
		(duplicate_pad_numbers_are_jumpers no)
		(fp_line
			(start -0.7874 0.4064)
			(end -0.7874 -0.4064)
			(stroke
				(width 0.1524)
				(type default)
			)
			(layer "F.SilkS")
		)
		(fp_line
			(start 0.7874 0.4064)
			(end -0.7874 0.4064)
			(stroke
				(width 0.1524)
				(type default)
			)
			(layer "F.SilkS")
		)
		(fp_line
			(start -0.7874 -0.4064)
			(end 0.7874 -0.4064)
			(stroke
				(width 0.1524)
				(type default)
			)
			(layer "F.SilkS")
		)
		(fp_line
			(start 0.7874 -0.4064)
			(end 0.7874 0.4064)
			(stroke
				(width 0.1524)
				(type default)
			)
			(layer "F.SilkS")
		)
		(fp_line
			(start -0.67945 0.3048)
			(end -0.67945 -0.305054)
			(stroke
				(width 0.1)
				(type default)
			)
			(layer "F.Fab")
		)
		(fp_line
			(start -0.12065 0.3048)
			(end -0.67945 0.3048)
			(stroke
				(width 0.1)
				(type default)
			)
			(layer "F.Fab")
		)
		(fp_line
			(start 0.120396 0.3048)
			(end 0.120396 0.2794)
			(stroke
				(width 0.1)
				(type default)
			)
			(layer "F.Fab")
		)
		(fp_line
			(start 0.67945 0.3048)
			(end 0.120396 0.3048)
			(stroke
				(width 0.1)
				(type default)
			)
			(layer "F.Fab")
		)
		(fp_line
			(start -0.12065 0.2794)
			(end -0.12065 0.3048)
			(stroke
				(width 0.1)
				(type default)
			)
			(layer "F.Fab")
		)
		(fp_line
			(start 0.120396 0.2794)
			(end -0.12065 0.2794)
			(stroke
				(width 0.1)
				(type default)
			)
			(layer "F.Fab")
		)
		(fp_line
			(start -0.12065 -0.2794)
			(end 0.12065 -0.2794)
			(stroke
				(width 0.1)
				(type default)
			)
			(layer "F.Fab")
		)
		(fp_line
			(start 0.12065 -0.2794)
			(end 0.12065 -0.3048)
			(stroke
				(width 0.1)
				(type default)
			)
			(layer "F.Fab")
		)
		(fp_line
			(start 0.12065 -0.3048)
			(end 0.67945 -0.3048)
			(stroke
				(width 0.1)
				(type default)
			)
			(layer "F.Fab")
		)
		(fp_line
			(start 0.67945 -0.3048)
			(end 0.67945 0.3048)
			(stroke
				(width 0.1)
				(type default)
			)
			(layer "F.Fab")
		)
		(fp_line
			(start -0.67945 -0.305054)
			(end -0.12065 -0.305054)
			(stroke
				(width 0.1)
				(type default)
			)
			(layer "F.Fab")
		)
		(fp_line
			(start -0.12065 -0.305054)
			(end -0.12065 -0.2794)
			(stroke
				(width 0.1)
				(type default)
			)
			(layer "F.Fab")
		)
		(pad "1" smd circle
			(at -0.40005 0 270)
			(size 0 0)
			(layers "F.Cu" "F.Mask" "F.Paste")
			(net "HP_LVC3_OCP_V3_1_P12V_PWRGD")
		)
		(pad "2" smd circle
			(at 0.40005 0 270)
			(size 0 0)
			(layers "F.Cu" "F.Mask" "F.Paste")
			(net "P3V3_OCP_EN_1_R2")
		)
	)
	(footprint ""
		(layer "F.Cu")
		(at 308.198266 -430.240186 180)
		(property "Reference" "R4135"
			(at 0 0 180)
			(layer "F.SilkS")
			(hide yes)
			(effects
				(font
					(size 1.27 1.27)
				)
			)
		)
		(property "Value" ""
			(at 0 0 180)
			(layer "F.Fab")
			(effects
				(font
					(size 1.27 1.27)
				)
			)
		)
		(duplicate_pad_numbers_are_jumpers no)
		(fp_line
			(start 0.7874 0.4064)
			(end -0.7874 0.4064)
			(stroke
				(width 0.1524)
				(type default)
			)
			(layer "F.SilkS")
		)
		(fp_line
			(start 0.7874 -0.4064)
			(end 0.7874 0.4064)
			(stroke
				(width 0.1524)
				(type default)
			)
			(layer "F.SilkS")
		)
		(fp_line
			(start -0.7874 0.4064)
			(end -0.7874 -0.4064)
			(stroke
				(width 0.1524)
				(type default)
			)
			(layer "F.SilkS")
		)
		(fp_line
			(start -0.7874 -0.4064)
			(end 0.7874 -0.4064)
			(stroke
				(width 0.1524)
				(type default)
			)
			(layer "F.SilkS")
		)
		(fp_line
			(start 0.67945 0.3048)
			(end 0.120396 0.3048)
			(stroke
				(width 0.1)
				(type default)
			)
			(layer "F.Fab")
		)
		(fp_line
			(start 0.67945 -0.3048)
			(end 0.67945 0.3048)
			(stroke
				(width 0.1)
				(type default)
			)
			(layer "F.Fab")
		)
		(fp_line
			(start 0.12065 -0.2794)
			(end 0.12065 -0.3048)
			(stroke
				(width 0.1)
				(type default)
			)
			(layer "F.Fab")
		)
		(fp_line
			(start 0.12065 -0.3048)
			(end 0.67945 -0.3048)
			(stroke
				(width 0.1)
				(type default)
			)
			(layer "F.Fab")
		)
		(fp_line
			(start 0.120396 0.3048)
			(end 0.120396 0.2794)
			(stroke
				(width 0.1)
				(type default)
			)
			(layer "F.Fab")
		)
		(fp_line
			(start 0.120396 0.2794)
			(end -0.12065 0.2794)
			(stroke
				(width 0.1)
				(type default)
			)
			(layer "F.Fab")
		)
		(fp_line
			(start -0.12065 0.3048)
			(end -0.67945 0.3048)
			(stroke
				(width 0.1)
				(type default)
			)
			(layer "F.Fab")
		)
		(fp_line
			(start -0.12065 0.2794)
			(end -0.12065 0.3048)
			(stroke
				(width 0.1)
				(type default)
			)
			(layer "F.Fab")
		)
		(fp_line
			(start -0.12065 -0.2794)
			(end 0.12065 -0.2794)
			(stroke
				(width 0.1)
				(type default)
			)
			(layer "F.Fab")
		)
		(fp_line
			(start -0.12065 -0.305054)
			(end -0.12065 -0.2794)
			(stroke
				(width 0.1)
				(type default)
			)
			(layer "F.Fab")
		)
		(fp_line
			(start -0.67945 0.3048)
			(end -0.67945 -0.305054)
			(stroke
				(width 0.1)
				(type default)
			)
			(layer "F.Fab")
		)
		(fp_line
			(start -0.67945 -0.305054)
			(end -0.12065 -0.305054)
			(stroke
				(width 0.1)
				(type default)
			)
			(layer "F.Fab")
		)
		(pad "1" smd circle
			(at -0.40005 0 180)
			(size 0 0)
			(layers "F.Cu" "F.Mask" "F.Paste")
			(net "P3V3_AUX")
		)
		(pad "2" smd circle
			(at 0.40005 0 180)
			(size 0 0)
			(layers "F.Cu" "F.Mask" "F.Paste")
			(net "PRSNT_CABLE_GPU_A2_N")
		)
	)
	(footprint ""
		(layer "F.Cu")
		(at 144.74063 -98.355658)
		(property "Reference" "U246"
			(at 0.1651 -1.72847 0)
			(unlocked yes)
			(layer "F.SilkS")
			(effects
				(font
					(size 0.7874 0.5842)
					(thickness 0.1524)
				)
			)
		)
		(property "Value" ""
			(at 0 0 0)
			(layer "F.Fab")
			(effects
				(font
					(size 1.27 1.27)
				)
			)
		)
		(duplicate_pad_numbers_are_jumpers no)
		(fp_line
			(start -1.7272 1.1176)
			(end -1.7272 -1.1176)
			(stroke
				(width 0.1524)
				(type default)
			)
			(layer "F.SilkS")
		)
		(fp_line
			(start -0.254 -1.1176)
			(end -1.7272 -1.1176)
			(stroke
				(width 0.1524)
				(type default)
			)
			(layer "F.SilkS")
		)
		(fp_line
			(start 0 -0.7366)
			(end -0.254 -1.1176)
			(stroke
				(width 0.1524)
				(type default)
			)
			(layer "F.SilkS")
		)
		(fp_line
			(start 0.254 -1.1176)
			(end 0 -0.7366)
			(stroke
				(width 0.1524)
				(type default)
			)
			(layer "F.SilkS")
		)
		(fp_line
			(start 1.7272 -1.1176)
			(end 0.254 -1.1176)
			(stroke
				(width 0.1524)
				(type default)
			)
			(layer "F.SilkS")
		)
		(fp_line
			(start 1.7272 -1.1176)
			(end 1.7272 1.1176)
			(stroke
				(width 0.1524)
				(type default)
			)
			(layer "F.SilkS")
		)
		(fp_line
			(start 1.7272 1.1176)
			(end -1.7272 1.1176)
			(stroke
				(width 0.1524)
				(type default)
			)
			(layer "F.SilkS")
		)
		(fp_poly
			(pts
				(xy -2.7178 -1.030986) (xy -1.9558 -0.649986) (xy -2.7178 -0.268986)
			)
			(stroke
				(width 0)
				(type default)
			)
			(fill yes)
			(layer "F.SilkS")
		)
		(fp_line
			(start -1.5748 -1.1176)
			(end -1.5748 1.1176)
			(stroke
				(width 0.1)
				(type default)
			)
			(layer "F.Fab")
		)
		(fp_line
			(start -1.5748 1.1176)
			(end 1.5748 1.1176)
			(stroke
				(width 0.1)
				(type default)
			)
			(layer "F.Fab")
		)
		(fp_line
			(start 1.5748 -1.1176)
			(end -1.5748 -1.1176)
			(stroke
				(width 0.1)
				(type default)
			)
			(layer "F.Fab")
		)
		(fp_line
			(start 1.5748 1.1176)
			(end 1.5748 -1.1176)
			(stroke
				(width 0.1)
				(type default)
			)
			(layer "F.Fab")
		)
		(fp_poly
			(pts
				(xy -1.9558 -0.649986) (xy -2.7178 -0.268986) (xy -2.7178 -1.030986)
			)
			(stroke
				(width 0)
				(type default)
			)
			(fill yes)
			(layer "F.Fab")
		)
		(pad "1" smd rect
			(at -0.999998 -0.649986 270)
			(size 0.3556 1.1176)
			(layers "F.Cu" "F.Mask" "F.Paste")
			(net "OCP_V3_2_NOT_PRSNT_RBT_ARB_IN")
		)
		(pad "2" smd rect
			(at -0.999998 0 270)
			(size 0.3556 1.1176)
			(layers "F.Cu" "F.Mask" "F.Paste")
			(net "GND")
		)
		(pad "3" smd rect
			(at -0.999998 0.649986 270)
			(size 0.3556 1.1176)
			(layers "F.Cu" "F.Mask" "F.Paste")
			(net "OCP_V3_2_RBT_ARB_OUT")
		)
		(pad "4" smd rect
			(at 0.999998 0.649986 270)
			(size 0.3556 1.1176)
			(layers "F.Cu" "F.Mask" "F.Paste")
			(net "OCP_SFF_RBT_ARB_IN_MUX1")
		)
		(pad "5" smd rect
			(at 0.999998 0 270)
			(size 0.3556 1.1176)
			(layers "F.Cu" "F.Mask" "F.Paste")
			(net "P3V3_AUX")
		)
		(pad "6" smd rect
			(at 0.999998 -0.649986 270)
			(size 0.3556 1.1176)
			(layers "F.Cu" "F.Mask" "F.Paste")
			(net "OCP_V3_2_PRSNT_ALL_R1_N")
		)
	)
)
